# S9S_MB_2U (Grand Teton) — schematic netlist excerpt (pin names and nets, part order shuffled) for the footprints in the layout excerpt that follows; sources: Cadence DE-HDL packaged netlist, KiCad conversion of 03242023_DA0F0TMBIJ0_F0T_Motherboard_J_brd_V01_OCP.brd

R3679  Q_RES  0 5% EMPTY  pkg 0402LF  page 250 : A = P12V_AUX_ADC ; B = P12V_AUX_ADC_MAM
C226  Q_CAP  10UF 6.3V 20% X6S  pkg C0402  page 77 : A = PVCCIN_CPU1 ; B = GND

(kicad_pcb
	(version 20260206)
	(generator "pcbnew")
	(generator_version "10.0")
	(general
		(thickness 1.6)
		(legacy_teardrops no)
	)
	(paper "A4")
	(title_block
		(title "03242023_DA0F0TMBIJ0_F0T_Motherboard_J_brd_V01_OCP.brd")
		(comment 1 "Grand Teton / footprints 3303-3304 of 6105")
	)
	(layers
		(0 "F.Cu" signal "TOP")
		(4 "In1.Cu" signal "GND")
		(6 "In2.Cu" signal "IN1")
		(8 "In3.Cu" signal "GND1")
		(10 "In4.Cu" signal "IN2")
		(12 "In5.Cu" signal "GND2")
		(14 "In6.Cu" signal "IN3")
		(16 "In7.Cu" signal "GND3")
		(18 "In8.Cu" signal "VCC")
		(20 "In9.Cu" signal "VCC1")
		(22 "In10.Cu" signal "GND4")
		(24 "In11.Cu" signal "IN4")
		(26 "In12.Cu" signal "GND5")
		(28 "In13.Cu" signal "IN5")
		(30 "In14.Cu" signal "GND6")
		(32 "In15.Cu" signal "IN6")
		(34 "In16.Cu" signal "GND7")
		(2 "B.Cu" signal "BOTTOM")
		(9 "F.Adhes" user "F.Adhesive")
		(11 "B.Adhes" user "B.Adhesive")
		(13 "F.Paste" user "Package Geometry/Pastemask Top")
		(15 "B.Paste" user "Package Geometry/Pastemask Bottom")
		(5 "F.SilkS" user "Ref Des/Silkscreen Top")
		(7 "B.SilkS" user "Ref Des/Silkscreen Bottom")
		(1 "F.Mask" user "Board Geometry/Soldermask Top")
		(3 "B.Mask" user "Board Geometry/Soldermask Bottom")
		(17 "Dwgs.User" user "User.Drawings")
		(19 "Cmts.User" user "User.Comments")
		(21 "Eco1.User" user "User.Eco1")
		(23 "Eco2.User" user "User.Eco2")
		(25 "Edge.Cuts" user "Board Geometry/Outline")
		(27 "Margin" user)
		(31 "F.CrtYd" user "Package Geometry/Place Bound Top")
		(29 "B.CrtYd" user "Package Geometry/Place Bound Bottom")
		(35 "F.Fab" user "Ref Des/Assembly Top")
		(33 "B.Fab" user "Ref Des/Assembly Bottom")
	)
	(footprint ""
		(layer "F.Cu")
		(at 106.322114 -258.72694 90)
		(property "Reference" "C226"
			(at 0 0 90)
			(layer "F.SilkS")
			(hide yes)
			(effects
				(font
					(size 1.27 1.27)
				)
			)
		)
		(property "Value" ""
			(at 0 0 90)
			(layer "F.Fab")
			(effects
				(font
					(size 1.27 1.27)
				)
			)
		)
		(duplicate_pad_numbers_are_jumpers no)
		(fp_line
			(start 0.7874 -0.4064)
			(end 0.7874 0.4064)
			(stroke
				(width 0.1524)
				(type default)
			)
			(layer "F.SilkS")
		)
		(fp_line
			(start -0.7874 -0.4064)
			(end 0.7874 -0.4064)
			(stroke
				(width 0.1524)
				(type default)
			)
			(layer "F.SilkS")
		)
		(fp_line
			(start 0.7874 0.4064)
			(end -0.7874 0.4064)
			(stroke
				(width 0.1524)
				(type default)
			)
			(layer "F.SilkS")
		)
		(fp_line
			(start -0.7874 0.4064)
			(end -0.7874 -0.4064)
			(stroke
				(width 0.1524)
				(type default)
			)
			(layer "F.SilkS")
		)
		(fp_line
			(start -0.12065 -0.305054)
			(end -0.12065 -0.2794)
			(stroke
				(width 0.1)
				(type default)
			)
			(layer "F.Fab")
		)
		(fp_line
			(start -0.67945 -0.305054)
			(end -0.12065 -0.305054)
			(stroke
				(width 0.1)
				(type default)
			)
			(layer "F.Fab")
		)
		(fp_line
			(start 0.67945 -0.3048)
			(end 0.67945 0.3048)
			(stroke
				(width 0.1)
				(type default)
			)
			(layer "F.Fab")
		)
		(fp_line
			(start 0.12065 -0.3048)
			(end 0.67945 -0.3048)
			(stroke
				(width 0.1)
				(type default)
			)
			(layer "F.Fab")
		)
		(fp_line
			(start 0.12065 -0.2794)
			(end 0.12065 -0.3048)
			(stroke
				(width 0.1)
				(type default)
			)
			(layer "F.Fab")
		)
		(fp_line
			(start -0.12065 -0.2794)
			(end 0.12065 -0.2794)
			(stroke
				(width 0.1)
				(type default)
			)
			(layer "F.Fab")
		)
		(fp_line
			(start 0.120396 0.2794)
			(end -0.12065 0.2794)
			(stroke
				(width 0.1)
				(type default)
			)
			(layer "F.Fab")
		)
		(fp_line
			(start -0.12065 0.2794)
			(end -0.12065 0.3048)
			(stroke
				(width 0.1)
				(type default)
			)
			(layer "F.Fab")
		)
		(fp_line
			(start 0.67945 0.3048)
			(end 0.120396 0.3048)
			(stroke
				(width 0.1)
				(type default)
			)
			(layer "F.Fab")
		)
		(fp_line
			(start 0.120396 0.3048)
			(end 0.120396 0.2794)
			(stroke
				(width 0.1)
				(type default)
			)
			(layer "F.Fab")
		)
		(fp_line
			(start -0.12065 0.3048)
			(end -0.67945 0.3048)
			(stroke
				(width 0.1)
				(type default)
			)
			(layer "F.Fab")
		)
		(fp_line
			(start -0.67945 0.3048)
			(end -0.67945 -0.305054)
			(stroke
				(width 0.1)
				(type default)
			)
			(layer "F.Fab")
		)
		(pad "1" smd circle
			(at -0.40005 0 90)
			(size 0 0)
			(layers "F.Cu" "F.Mask" "F.Paste")
			(net "PVCCIN_CPU1")
		)
		(pad "2" smd circle
			(at 0.40005 0 90)
			(size 0 0)
			(layers "F.Cu" "F.Mask" "F.Paste")
			(net "GND")
		)
	)
	(footprint ""
		(layer "F.Cu")
		(at 40.627554 -112.603026)
		(property "Reference" "R3679"
			(at 0 0 0)
			(layer "F.SilkS")
			(hide yes)
			(effects
				(font
					(size 1.27 1.27)
				)
			)
		)
		(property "Value" ""
			(at 0 0 0)
			(layer "F.Fab")
			(effects
				(font
					(size 1.27 1.27)
				)
			)
		)
		(duplicate_pad_numbers_are_jumpers no)
		(fp_line
			(start -0.7874 -0.4064)
			(end 0.7874 -0.4064)
			(stroke
				(width 0.1524)
				(type default)
			)
			(layer "F.SilkS")
		)
		(fp_line
			(start -0.7874 0.4064)
			(end -0.7874 -0.4064)
			(stroke
				(width 0.1524)
				(type default)
			)
			(layer "F.SilkS")
		)
		(fp_line
			(start 0.7874 -0.4064)
			(end 0.7874 0.4064)
			(stroke
				(width 0.1524)
				(type default)
			)
			(layer "F.SilkS")
		)
		(fp_line
			(start 0.7874 0.4064)
			(end -0.7874 0.4064)
			(stroke
				(width 0.1524)
				(type default)
			)
			(layer "F.SilkS")
		)
		(fp_line
			(start -0.67945 -0.305054)
			(end -0.12065 -0.305054)
			(stroke
				(width 0.1)
				(type default)
			)
			(layer "F.Fab")
		)
		(fp_line
			(start -0.67945 0.3048)
			(end -0.67945 -0.305054)
			(stroke
				(width 0.1)
				(type default)
			)
			(layer "F.Fab")
		)
		(fp_line
			(start -0.12065 -0.305054)
			(end -0.12065 -0.2794)
			(stroke
				(width 0.1)
				(type default)
			)
			(layer "F.Fab")
		)
		(fp_line
			(start -0.12065 -0.2794)
			(end 0.12065 -0.2794)
			(stroke
				(width 0.1)
				(type default)
			)
			(layer "F.Fab")
		)
		(fp_line
			(start -0.12065 0.2794)
			(end -0.12065 0.3048)
			(stroke
				(width 0.1)
				(type default)
			)
			(layer "F.Fab")
		)
		(fp_line
			(start -0.12065 0.3048)
			(end -0.67945 0.3048)
			(stroke
				(width 0.1)
				(type default)
			)
			(layer "F.Fab")
		)
		(fp_line
			(start 0.120396 0.2794)
			(end -0.12065 0.2794)
			(stroke
				(width 0.1)
				(type default)
			)
			(layer "F.Fab")
		)
		(fp_line
			(start 0.120396 0.3048)
			(end 0.120396 0.2794)
			(stroke
				(width 0.1)
				(type default)
			)
			(layer "F.Fab")
		)
		(fp_line
			(start 0.12065 -0.3048)
			(end 0.67945 -0.3048)
			(stroke
				(width 0.1)
				(type default)
			)
			(layer "F.Fab")
		)
		(fp_line
			(start 0.12065 -0.2794)
			(end 0.12065 -0.3048)
			(stroke
				(width 0.1)
				(type default)
			)
			(layer "F.Fab")
		)
		(fp_line
			(start 0.67945 -0.3048)
			(end 0.67945 0.3048)
			(stroke
				(width 0.1)
				(type default)
			)
			(layer "F.Fab")
		)
		(fp_line
			(start 0.67945 0.3048)
			(end 0.120396 0.3048)
			(stroke
				(width 0.1)
				(type default)
			)
			(layer "F.Fab")
		)
		(pad "1" smd rect
			(at -0.40005 0 180)
			(size 0.4572 0.508)
			(layers "F.Cu" "F.Mask" "F.Paste")
			(net "P12V_AUX_ADC")
		)
		(pad "2" smd rect
			(at 0.40005 0 180)
			(size 0.4572 0.508)
			(layers "F.Cu" "F.Mask" "F.Paste")
			(net "P12V_AUX_ADC_MAM")
		)
	)
)
